(kicad_pcb
	(version 20241229)
	(generator "pcbnew")
	(generator_version "9.0")
	(general
		(thickness 1.62)
		(legacy_teardrops no)
	)
	(paper "A4")
	(title_block
		(title "OCuLink to 10GbE adapter")
		(date "2026-02-23")
		(rev "1.1.0")
		(company "Antmicro Ltd")
		(comment 1 "www.antmicro.com")
		(comment 9 "footprints 183-188 of 510")
	)
	(layers
		(0 "F.Cu" signal)
		(4 "In1.Cu" signal)
		(6 "In2.Cu" signal)
		(8 "In3.Cu" signal)
		(10 "In4.Cu" signal)
		(12 "In5.Cu" signal)
		(14 "In6.Cu" signal)
		(2 "B.Cu" signal)
		(9 "F.Adhes" user "F.Adhesive")
		(11 "B.Adhes" user "B.Adhesive")
		(13 "F.Paste" user)
		(15 "B.Paste" user)
		(5 "F.SilkS" user "F.Silkscreen")
		(7 "B.SilkS" user "B.Silkscreen")
		(1 "F.Mask" user)
		(3 "B.Mask" user)
		(17 "Dwgs.User" user "User.Drawings")
		(19 "Cmts.User" user "User.Comments")
		(21 "Eco1.User" user "User.Eco1")
		(23 "Eco2.User" user "User.Eco2")
		(25 "Edge.Cuts" user)
		(27 "Margin" user)
		(31 "F.CrtYd" user "F.Courtyard")
		(29 "B.CrtYd" user "B.Courtyard")
		(35 "F.Fab" user)
		(33 "B.Fab" user)
	)
	(footprint "antmicro-footprints:R_0402_1005Metric"
		(layer "F.Cu")
		(at 58.1 108.25 90)
		(descr "Resistor SMD 0402")
		(tags "resistor SMD 0402")
		(property "Reference" "R25"
			(at -1.32 1.25 90)
			(layer "F.SilkS")
			(effects
				(font
					(size 0.7 0.7)
					(thickness 0.15)
				)
				(justify left bottom)
			)
		)
		(property "Value" "R_100k_0402"
			(at -1.011843 1.772046 90)
			(layer "F.Fab")
			(hide yes)
			(effects
				(font
					(size 0.7 0.7)
					(thickness 0.15)
				)
				(justify left bottom)
			)
		)
		(property "Datasheet" "https://www.bourns.com/docs/product-datasheets/cr.pdf"
			(at 0 0 90)
			(layer "F.Fab")
			(hide yes)
			(effects
				(font
					(size 1.27 1.27)
					(thickness 0.15)
				)
			)
		)
		(property "Description" "SMD Chip Resistor, 100 kohm, ± 1%, 62.5 mW, 0402 [1005 Metric], Thick Film, General Purpose"
			(at 0 0 90)
			(layer "F.Fab")
			(hide yes)
			(effects
				(font
					(size 1.27 1.27)
					(thickness 0.15)
				)
			)
		)
		(property "MPN" "CR0402-FX-1003GLF"
			(at 0 0 90)
			(unlocked yes)
			(layer "F.Fab")
			(hide yes)
			(effects
				(font
					(size 1 1)
					(thickness 0.15)
				)
			)
		)
		(property "Manufacturer" "Bourns"
			(at 0 0 90)
			(unlocked yes)
			(layer "F.Fab")
			(hide yes)
			(effects
				(font
					(size 1 1)
					(thickness 0.15)
				)
			)
		)
		(property "License" "Apache-2.0"
			(at 0 0 90)
			(unlocked yes)
			(layer "F.Fab")
			(hide yes)
			(effects
				(font
					(size 1 1)
					(thickness 0.15)
				)
			)
		)
		(property "Author" "Antmicro"
			(at 0 0 90)
			(unlocked yes)
			(layer "F.Fab")
			(hide yes)
			(effects
				(font
					(size 1 1)
					(thickness 0.15)
				)
			)
		)
		(property "Val" "100k"
			(at 0 0 90)
			(unlocked yes)
			(layer "F.Fab")
			(hide yes)
			(effects
				(font
					(size 1 1)
					(thickness 0.15)
				)
			)
		)
		(property "Tolerance" "1%"
			(at 0 0 90)
			(unlocked yes)
			(layer "F.Fab")
			(hide yes)
			(effects
				(font
					(size 1 1)
					(thickness 0.15)
				)
			)
		)
		(sheetname "/Power/")
		(sheetfile "power.kicad_sch")
		(attr smd)
		(fp_rect
			(start -0.925 -0.47)
			(end 0.925 0.47)
			(stroke
				(width 0.05)
				(type default)
			)
			(fill no)
			(layer "F.CrtYd")
		)
		(fp_rect
			(start -0.5 -0.25)
			(end 0.5 0.25)
			(stroke
				(width 0.15)
				(type solid)
			)
			(fill no)
			(layer "F.Fab")
		)
		(pad "1" smd roundrect
			(at -0.48 0 90)
			(size 0.59 0.64)
			(layers "F.Cu" "F.Mask" "F.Paste")
			(roundrect_rratio 0.25)
			(net 341 "/Power/1V0_PG")
			(pintype "passive")
		)
		(pad "2" smd roundrect
			(at 0.48 0 90)
			(size 0.59 0.64)
			(layers "F.Cu" "F.Mask" "F.Paste")
			(roundrect_rratio 0.25)
			(net 328 "/Power/1V0_VCC")
			(pintype "passive")
		)
	)
	(footprint "antmicro-footprints:R_0402_1005Metric"
		(layer "F.Cu")
		(at 81.95 57.771999 180)
		(descr "Resistor SMD 0402")
		(tags "resistor SMD 0402")
		(property "Reference" "R22"
			(at -1.2 -0.560001 0)
			(layer "F.SilkS")
			(effects
				(font
					(size 0.7 0.7)
					(thickness 0.15)
				)
				(justify right top)
			)
		)
		(property "Value" "R_5k1_0402"
			(at -1.011843 1.772046 0)
			(layer "F.Fab")
			(hide yes)
			(effects
				(font
					(size 0.7 0.7)
					(thickness 0.15)
				)
				(justify right top)
			)
		)
		(property "Datasheet" "https://www.bourns.com/docs/product-datasheets/cr.pdf"
			(at 0 0 0)
			(layer "F.Fab")
			(hide yes)
			(effects
				(font
					(size 1.27 1.27)
					(thickness 0.15)
				)
			)
		)
		(property "Description" "SMD Chip Resistor, 5.1 kohm, ± 1%, 63 mW, 0402 [1005 Metric], Thick Film, General Purpose"
			(at 0 0 0)
			(layer "F.Fab")
			(hide yes)
			(effects
				(font
					(size 1.27 1.27)
					(thickness 0.15)
				)
			)
		)
		(property "MPN" "CR0402-FX-5101GLF"
			(at 0 0 180)
			(unlocked yes)
			(layer "F.Fab")
			(hide yes)
			(effects
				(font
					(size 1 1)
					(thickness 0.15)
				)
			)
		)
		(property "Manufacturer" "Bourns"
			(at 0 0 180)
			(unlocked yes)
			(layer "F.Fab")
			(hide yes)
			(effects
				(font
					(size 1 1)
					(thickness 0.15)
				)
			)
		)
		(property "License" "Apache-2.0"
			(at 0 0 180)
			(unlocked yes)
			(layer "F.Fab")
			(hide yes)
			(effects
				(font
					(size 1 1)
					(thickness 0.15)
				)
			)
		)
		(property "Author" "Antmicro"
			(at 0 0 180)
			(unlocked yes)
			(layer "F.Fab")
			(hide yes)
			(effects
				(font
					(size 1 1)
					(thickness 0.15)
				)
			)
		)
		(property "Val" "5k1"
			(at 0 0 180)
			(unlocked yes)
			(layer "F.Fab")
			(hide yes)
			(effects
				(font
					(size 1 1)
					(thickness 0.15)
				)
			)
		)
		(property "Tolerance" "1%"
			(at 0 0 180)
			(unlocked yes)
			(layer "F.Fab")
			(hide yes)
			(effects
				(font
					(size 1 1)
					(thickness 0.15)
				)
			)
		)
		(sheetname "/Power/")
		(sheetfile "power.kicad_sch")
		(attr smd)
		(fp_rect
			(start -0.925 -0.47)
			(end 0.925 0.47)
			(stroke
				(width 0.05)
				(type default)
			)
			(fill no)
			(layer "F.CrtYd")
		)
		(fp_rect
			(start -0.5 -0.25)
			(end 0.5 0.25)
			(stroke
				(width 0.15)
				(type solid)
			)
			(fill no)
			(layer "F.Fab")
		)
		(pad "1" smd roundrect
			(at -0.48 0 180)
			(size 0.59 0.64)
			(layers "F.Cu" "F.Mask" "F.Paste")
			(roundrect_rratio 0.25)
			(net 28 "GND")
			(pintype "passive")
		)
		(pad "2" smd roundrect
			(at 0.48 0 180)
			(size 0.59 0.64)
			(layers "F.Cu" "F.Mask" "F.Paste")
			(roundrect_rratio 0.25)
			(net 356 "/Power/CC2")
			(pintype "passive")
		)
	)
	(footprint "antmicro-footprints:C_0402_1005Metric"
		(layer "F.Cu")
		(at 56.399998 105.500002)
		(descr "Capacitor SMD 0402")
		(tags "capacitor SMD 0402")
		(property "Reference" "C19"
			(at -2.959998 0.369998 0)
			(layer "F.SilkS")
			(effects
				(font
					(size 0.7 0.7)
					(thickness 0.15)
				)
				(justify left bottom)
			)
		)
		(property "Value" "C_100n_0402"
			(at -1.022927 2.155213 0)
			(layer "F.Fab")
			(hide yes)
			(effects
				(font
					(size 0.7 0.7)
					(thickness 0.15)
				)
				(justify left bottom)
			)
		)
		(property "Datasheet" "https://www.murata.com/products/productdetail?partno=GRM155R61H104KE14%23"
			(at 0 0 0)
			(layer "F.Fab")
			(hide yes)
			(effects
				(font
					(size 1.27 1.27)
					(thickness 0.15)
				)
			)
		)
		(property "Description" "SMD Multilayer Ceramic Capacitor, 0.1 µF, 50 V, 0402 [1005 Metric], ± 10%, X5R, GRM Series"
			(at 0 0 0)
			(layer "F.Fab")
			(hide yes)
			(effects
				(font
					(size 1.27 1.27)
					(thickness 0.15)
				)
			)
		)
		(property "MPN" "GRM155R61H104KE14D"
			(at 0 0 0)
			(unlocked yes)
			(layer "F.Fab")
			(hide yes)
			(effects
				(font
					(size 1 1)
					(thickness 0.15)
				)
			)
		)
		(property "Manufacturer" "Murata"
			(at 0 0 0)
			(unlocked yes)
			(layer "F.Fab")
			(hide yes)
			(effects
				(font
					(size 1 1)
					(thickness 0.15)
				)
			)
		)
		(property "License" "Apache-2.0"
			(at 0 0 0)
			(unlocked yes)
			(layer "F.Fab")
			(hide yes)
			(effects
				(font
					(size 1 1)
					(thickness 0.15)
				)
			)
		)
		(property "Author" "Antmicro"
			(at 0 0 0)
			(unlocked yes)
			(layer "F.Fab")
			(hide yes)
			(effects
				(font
					(size 1 1)
					(thickness 0.15)
				)
			)
		)
		(property "Val" "100n"
			(at 0 0 0)
			(unlocked yes)
			(layer "F.Fab")
			(hide yes)
			(effects
				(font
					(size 1 1)
					(thickness 0.15)
				)
			)
		)
		(property "Voltage" "50V"
			(at 0 0 0)
			(unlocked yes)
			(layer "F.Fab")
			(hide yes)
			(effects
				(font
					(size 1 1)
					(thickness 0.15)
				)
			)
		)
		(property "Dielectric" "X5R"
			(at 0 0 0)
			(unlocked yes)
			(layer "F.Fab")
			(hide yes)
			(effects
				(font
					(size 1 1)
					(thickness 0.15)
				)
			)
		)
		(sheetname "/Power/")
		(sheetfile "power.kicad_sch")
		(attr smd)
		(fp_rect
			(start -0.925 -0.47)
			(end 0.925 0.47)
			(stroke
				(width 0.05)
				(type default)
			)
			(fill no)
			(layer "F.CrtYd")
		)
		(fp_line
			(start -0.494 -0.25)
			(end 0.504 -0.25)
			(stroke
				(width 0.15)
				(type solid)
			)
			(layer "F.Fab")
		)
		(fp_line
			(start -0.494 0.248)
			(end -0.494 -0.25)
			(stroke
				(width 0.15)
				(type solid)
			)
			(layer "F.Fab")
		)
		(fp_line
			(start 0.504 -0.25)
			(end 0.504 0.248)
			(stroke
				(width 0.15)
				(type solid)
			)
			(layer "F.Fab")
		)
		(fp_line
			(start 0.504 0.248)
			(end -0.494 0.248)
			(stroke
				(width 0.15)
				(type solid)
			)
			(layer "F.Fab")
		)
		(pad "1" smd roundrect
			(at -0.48 0)
			(size 0.59 0.64)
			(layers "F.Cu" "F.Mask" "F.Paste")
			(roundrect_rratio 0.25)
			(net 323 "/Power/1V88_BST")
			(pintype "passive")
		)
		(pad "2" smd roundrect
			(at 0.48 0)
			(size 0.59 0.64)
			(layers "F.Cu" "F.Mask" "F.Paste")
			(roundrect_rratio 0.25)
			(net 335 "/Power/1V88_SW")
			(pintype "passive")
		)
	)
	(footprint "antmicro-footprints:C_0402_1005Metric"
		(layer "F.Cu")
		(at 57.099999 85.15 -90)
		(descr "Capacitor SMD 0402")
		(tags "capacitor SMD 0402")
		(property "Reference" "C15"
			(at -2.93 -0.330001 90)
			(layer "F.SilkS")
			(effects
				(font
					(size 0.7 0.7)
					(thickness 0.15)
				)
				(justify right top)
			)
		)
		(property "Value" "C_1u_25V_0402"
			(at -1.022927 2.155213 90)
			(layer "F.Fab")
			(hide yes)
			(effects
				(font
					(size 0.7 0.7)
					(thickness 0.15)
				)
				(justify right top)
			)
		)
		(property "Datasheet" "https://www.murata.com/products/productdetail?partno=GRM155R61E105KE11%23"
			(at 0 0 90)
			(layer "F.Fab")
			(hide yes)
			(effects
				(font
					(size 1.27 1.27)
					(thickness 0.15)
				)
			)
		)
		(property "Description" "SMD Multilayer Ceramic Capacitor, 1 µF, 25 V, 0402 [1005 Metric], ± 10%, X5R, GRM Series"
			(at 0 0 90)
			(layer "F.Fab")
			(hide yes)
			(effects
				(font
					(size 1.27 1.27)
					(thickness 0.15)
				)
			)
		)
		(property "MPN" "GRM155R61E105KE11J"
			(at 0 0 270)
			(unlocked yes)
			(layer "F.Fab")
			(hide yes)
			(effects
				(font
					(size 1 1)
					(thickness 0.15)
				)
			)
		)
		(property "Manufacturer" "Murata"
			(at 0 0 270)
			(unlocked yes)
			(layer "F.Fab")
			(hide yes)
			(effects
				(font
					(size 1 1)
					(thickness 0.15)
				)
			)
		)
		(property "License" "Apache-2.0"
			(at 0 0 270)
			(unlocked yes)
			(layer "F.Fab")
			(hide yes)
			(effects
				(font
					(size 1 1)
					(thickness 0.15)
				)
			)
		)
		(property "Author" "Antmicro"
			(at 0 0 270)
			(unlocked yes)
			(layer "F.Fab")
			(hide yes)
			(effects
				(font
					(size 1 1)
					(thickness 0.15)
				)
			)
		)
		(property "Val" "1u"
			(at 0 0 270)
			(unlocked yes)
			(layer "F.Fab")
			(hide yes)
			(effects
				(font
					(size 1 1)
					(thickness 0.15)
				)
			)
		)
		(property "Voltage" "25V"
			(at 0 0 270)
			(unlocked yes)
			(layer "F.Fab")
			(hide yes)
			(effects
				(font
					(size 1 1)
					(thickness 0.15)
				)
			)
		)
		(property "Dielectric" "X5R"
			(at 0 0 270)
			(unlocked yes)
			(layer "F.Fab")
			(hide yes)
			(effects
				(font
					(size 1 1)
					(thickness 0.15)
				)
			)
		)
		(sheetname "/Power/")
		(sheetfile "power.kicad_sch")
		(attr smd)
		(fp_rect
			(start -0.925 -0.47)
			(end 0.925 0.47)
			(stroke
				(width 0.05)
				(type default)
			)
			(fill no)
			(layer "F.CrtYd")
		)
		(fp_line
			(start -0.494 0.248)
			(end -0.494 -0.25)
			(stroke
				(width 0.15)
				(type solid)
			)
			(layer "F.Fab")
		)
		(fp_line
			(start 0.504 0.248)
			(end -0.494 0.248)
			(stroke
				(width 0.15)
				(type solid)
			)
			(layer "F.Fab")
		)
		(fp_line
			(start -0.494 -0.25)
			(end 0.504 -0.25)
			(stroke
				(width 0.15)
				(type solid)
			)
			(layer "F.Fab")
		)
		(fp_line
			(start 0.504 -0.25)
			(end 0.504 0.248)
			(stroke
				(width 0.15)
				(type solid)
			)
			(layer "F.Fab")
		)
		(pad "1" smd roundrect
			(at -0.48 0 270)
			(size 0.59 0.64)
			(layers "F.Cu" "F.Mask" "F.Paste")
			(roundrect_rratio 0.25)
			(net 28 "GND")
			(pintype "passive")
		)
		(pad "2" smd roundrect
			(at 0.48 0 270)
			(size 0.59 0.64)
			(layers "F.Cu" "F.Mask" "F.Paste")
			(roundrect_rratio 0.25)
			(net 322 "/Power/VCCD_VCC")
			(pintype "passive")
		)
	)
	(footprint "antmicro-footprints:C_0603_1608Metric"
		(layer "F.Cu")
		(at 100.450001 101.999998)
		(descr "Capacitor SMD 0603")
		(tags "capacitor 0603")
		(property "Reference" "C159"
			(at 4.249999 0.450002 0)
			(layer "F.SilkS")
			(effects
				(font
					(size 0.7 0.7)
					(thickness 0.15)
				)
				(justify left bottom)
			)
		)
		(property "Value" "C_10u_10V_X7R_0603"
			(at -1.42757 1.770288 0)
			(layer "F.Fab")
			(hide yes)
			(effects
				(font
					(size 0.7 0.7)
					(thickness 0.15)
				)
				(justify left bottom)
			)
		)
		(property "Datasheet" "https://www.murata.com/products/productdetail?partno=GRM188Z71A106KA73%23"
			(at 0 0 0)
			(layer "F.Fab")
			(hide yes)
			(effects
				(font
					(size 1.27 1.27)
					(thickness 0.15)
				)
			)
		)
		(property "Description" "SMD Multilayer Ceramic Capacitor,  10µF, 10V, 0603, ±10%, X7R"
			(at 0 0 0)
			(layer "F.Fab")
			(hide yes)
			(effects
				(font
					(size 1.27 1.27)
					(thickness 0.15)
				)
			)
		)
		(property "MPN" "GRM188Z71A106KA73D"
			(at 0 0 0)
			(unlocked yes)
			(layer "F.Fab")
			(hide yes)
			(effects
				(font
					(size 1 1)
					(thickness 0.15)
				)
			)
		)
		(property "Val" "10u"
			(at 0 0 0)
			(unlocked yes)
			(layer "F.Fab")
			(hide yes)
			(effects
				(font
					(size 1 1)
					(thickness 0.15)
				)
			)
		)
		(property "Voltage" "10V"
			(at 0 0 0)
			(unlocked yes)
			(layer "F.Fab")
			(hide yes)
			(effects
				(font
					(size 1 1)
					(thickness 0.15)
				)
			)
		)
		(property "Dielectric" "X7R"
			(at 0 0 0)
			(unlocked yes)
			(layer "F.Fab")
			(hide yes)
			(effects
				(font
					(size 1 1)
					(thickness 0.15)
				)
			)
		)
		(property "Manufacturer" "Murata"
			(at 0 0 0)
			(unlocked yes)
			(layer "F.Fab")
			(hide yes)
			(effects
				(font
					(size 1 1)
					(thickness 0.15)
				)
			)
		)
		(property "License" "Apache-2.0"
			(at 0 0 0)
			(unlocked yes)
			(layer "F.Fab")
			(hide yes)
			(effects
				(font
					(size 1 1)
					(thickness 0.15)
				)
			)
		)
		(property "Author" "Antmicro"
			(at 0 0 0)
			(unlocked yes)
			(layer "F.Fab")
			(hide yes)
			(effects
				(font
					(size 1 1)
					(thickness 0.15)
				)
			)
		)
		(sheetname "/X710-AT2 power/")
		(sheetfile "x710-at2-power.kicad_sch")
		(attr smd)
		(fp_line
			(start -0.15 -0.4)
			(end 0.15 -0.4)
			(stroke
				(width 0.15)
				(type solid)
			)
			(layer "F.SilkS")
		)
		(fp_line
			(start -0.15 0.4)
			(end 0.15 0.4)
			(stroke
				(width 0.15)
				(type solid)
			)
			(layer "F.SilkS")
		)
		(fp_rect
			(start -1.25 -0.65)
			(end 1.25 0.65)
			(stroke
				(width 0.05)
				(type solid)
			)
			(fill no)
			(layer "F.CrtYd")
		)
		(fp_rect
			(start -0.8 -0.4)
			(end 0.8 0.4)
			(stroke
				(width 0.15)
				(type solid)
			)
			(fill no)
			(layer "F.Fab")
		)
		(pad "1" smd roundrect
			(at -0.7 0)
			(size 0.8 1)
			(layers "F.Cu" "F.Mask" "F.Paste")
			(roundrect_rratio 0.2)
			(net 28 "GND")
			(pintype "passive")
		)
		(pad "2" smd roundrect
			(at 0.7 0)
			(size 0.8 1)
			(layers "F.Cu" "F.Mask" "F.Paste")
			(roundrect_rratio 0.2)
			(net 1 "VCCA")
			(pintype "passive")
		)
	)
	(footprint "antmicro-footprints:L_Bourns-SRP4021HMT"
		(layer "F.Cu")
		(at 60.249999 88.450001 180)
		(property "Reference" "L2"
			(at -3.950001 2.250001 0)
			(layer "F.SilkS")
			(effects
				(font
					(size 0.7 0.7)
					(thickness 0.15)
				)
				(justify right top)
			)
		)
		(property "Value" "L_1u_10A_Bourns-SRP4021HMT"
			(at -2.85 3.4 0)
			(layer "F.Fab")
			(hide yes)
			(effects
				(font
					(size 0.7 0.7)
					(thickness 0.15)
				)
				(justify right top)
			)
		)
		(property "Datasheet" "https://www.mouser.com/datasheet/2/54/Bourns_04_01_2025_SRP4021HMT_Datasheet-3580094.pdf"
			(at 0 0 0)
			(layer "F.Fab")
			(hide yes)
			(effects
				(font
					(size 0.7 0.7)
					(thickness 0.15)
				)
				(justify right top)
			)
		)
		(property "Description" "Power Inductors - SMD Ind,4.1x4.2x1.9mm,1uH+/-20%,10A, Shielded"
			(at 0 0 0)
			(layer "F.Fab")
			(hide yes)
			(effects
				(font
					(size 0.7 0.7)
					(thickness 0.15)
				)
				(justify right top)
			)
		)
		(property "Val" "1u/10A"
			(at 0 0 180)
			(unlocked yes)
			(layer "F.Fab")
			(hide yes)
			(effects
				(font
					(size 1 1)
					(thickness 0.15)
				)
			)
		)
		(property "Manufacturer" "Bourns"
			(at 0 0 180)
			(unlocked yes)
			(layer "F.Fab")
			(hide yes)
			(effects
				(font
					(size 1 1)
					(thickness 0.15)
				)
			)
		)
		(property "MPN" "SRP4021HMT-1R0M"
			(at 0 0 180)
			(unlocked yes)
			(layer "F.Fab")
			(hide yes)
			(effects
				(font
					(size 1 1)
					(thickness 0.15)
				)
			)
		)
		(property "ISat" ""
			(at 0 0 180)
			(unlocked yes)
			(layer "F.Fab")
			(hide yes)
			(effects
				(font
					(size 1 1)
					(thickness 0.15)
				)
			)
		)
		(property "Isat" "8A"
			(at 0 0 180)
			(unlocked yes)
			(layer "F.Fab")
			(hide yes)
			(effects
				(font
					(size 1 1)
					(thickness 0.15)
				)
			)
		)
		(property "IMax" ""
			(at 0 0 180)
			(unlocked yes)
			(layer "F.Fab")
			(hide yes)
			(effects
				(font
					(size 1 1)
					(thickness 0.15)
				)
			)
		)
		(property "Imax" "10A"
			(at 0 0 180)
			(unlocked yes)
			(layer "F.Fab")
			(hide yes)
			(effects
				(font
					(size 1 1)
					(thickness 0.15)
				)
			)
		)
		(property "Size" "4.2x4.1"
			(at 0 0 180)
			(unlocked yes)
			(layer "F.Fab")
			(hide yes)
			(effects
				(font
					(size 1 1)
					(thickness 0.15)
				)
			)
		)
		(property "Author" "Antmicro"
			(at 0 0 180)
			(unlocked yes)
			(layer "F.Fab")
			(hide yes)
			(effects
				(font
					(size 1 1)
					(thickness 0.15)
				)
			)
		)
		(property "License" "Apache-2.0"
			(at 0 0 180)
			(unlocked yes)
			(layer "F.Fab")
			(hide yes)
			(effects
				(font
					(size 1 1)
					(thickness 0.15)
				)
			)
		)
		(sheetname "/Power/")
		(sheetfile "power.kicad_sch")
		(attr smd)
		(fp_line
			(start -0.8 2.05)
			(end 0.8 2.05)
			(stroke
				(width 0.15)
				(type solid)
			)
			(layer "F.SilkS")
		)
		(fp_line
			(start -0.8 -2.05)
			(end 0.8 -2.05)
			(stroke
				(width 0.15)
				(type solid)
			)
			(layer "F.SilkS")
		)
		(fp_rect
			(start -2.85 -2.3)
			(end 2.85 2.3)
			(stroke
				(width 0.05)
				(type solid)
			)
			(fill no)
			(layer "F.CrtYd")
		)
		(fp_rect
			(start -2 -2.05)
			(end 2 2.05)
			(stroke
				(width 0.15)
				(type solid)
			)
			(fill no)
			(layer "F.Fab")
		)
		(pad "1" smd rect
			(at 1.85 0)
			(size 1.5 3.5)
			(layers "F.Cu" "F.Mask" "F.Paste")
			(net 334 "/Power/VCCD_SW")
			(pintype "passive")
		)
		(pad "2" smd rect
			(at -1.85 0)
			(size 1.5 3.5)
			(layers "F.Cu" "F.Mask" "F.Paste")
			(net 303 "/Power/+VCCD_OUT")
			(pintype "passive")
		)
	)
)
